# T6G (Grand Teton) — schematic netlist excerpt (pin names and nets, part order shuffled) for the footprints in the layout excerpt that follows; sources: Cadence DE-HDL packaged netlist, KiCad conversion of 04192023_DAF0TMB3IC0_F0TG_MB_C_brd_V02_OCP.brd

R940  Q_RES  0 5% CHIP  pkg 0402LF  page 28 : A = BOOT_RDY_R_H ; B = BOOT_RDY_H
R4568  Q_RES  4.7K 1% CHIP  pkg 0402LF  page 257 : A = P1V581_PDB_ADC ; B = GND

(kicad_pcb
	(version 20260206)
	(generator "pcbnew")
	(generator_version "10.0")
	(general
		(thickness 1.6)
		(legacy_teardrops no)
	)
	(paper "A4")
	(title_block
		(title "04192023_DAF0TMB3IC0_F0TG_MB_C_brd_V02_OCP.brd")
		(comment 1 "Grand Teton / footprints 4278-4279 of 8354")
	)
	(layers
		(0 "F.Cu" signal "TOP")
		(4 "In1.Cu" signal "GND")
		(6 "In2.Cu" signal "IN1")
		(8 "In3.Cu" signal "GND1")
		(10 "In4.Cu" signal "IN2")
		(12 "In5.Cu" signal "GND2")
		(14 "In6.Cu" signal "IN3")
		(16 "In7.Cu" signal "GND3")
		(18 "In8.Cu" signal "VCC")
		(20 "In9.Cu" signal "VCC1")
		(22 "In10.Cu" signal "GND4")
		(24 "In11.Cu" signal "IN4")
		(26 "In12.Cu" signal "GND5")
		(28 "In13.Cu" signal "IN5")
		(30 "In14.Cu" signal "GND6")
		(32 "In15.Cu" signal "IN6")
		(34 "In16.Cu" signal "GND7")
		(2 "B.Cu" signal "BOTTOM")
		(9 "F.Adhes" user "F.Adhesive")
		(11 "B.Adhes" user "B.Adhesive")
		(13 "F.Paste" user "Package Geometry/Pastemask Top")
		(15 "B.Paste" user "Package Geometry/Pastemask Bottom")
		(5 "F.SilkS" user "Ref Des/Silkscreen Top")
		(7 "B.SilkS" user "Ref Des/Silkscreen Bottom")
		(1 "F.Mask" user "Board Geometry/Soldermask Top")
		(3 "B.Mask" user "Board Geometry/Soldermask Bottom")
		(17 "Dwgs.User" user "User.Drawings")
		(19 "Cmts.User" user "User.Comments")
		(21 "Eco1.User" user "User.Eco1")
		(23 "Eco2.User" user "User.Eco2")
		(25 "Edge.Cuts" user "Board Geometry/Outline")
		(27 "Margin" user)
		(31 "F.CrtYd" user "Package Geometry/Place Bound Top")
		(29 "B.CrtYd" user "Package Geometry/Place Bound Bottom")
		(35 "F.Fab" user "Ref Des/Assembly Top")
		(33 "B.Fab" user "Ref Des/Assembly Bottom")
	)
	(footprint ""
		(layer "F.Cu")
		(at 402.151088 -330.778612)
		(property "Reference" "R940"
			(at 0 0 0)
			(layer "F.SilkS")
			(hide yes)
			(effects
				(font
					(size 1.27 1.27)
				)
			)
		)
		(property "Value" ""
			(at 0 0 0)
			(layer "F.Fab")
			(effects
				(font
					(size 1.27 1.27)
				)
			)
		)
		(duplicate_pad_numbers_are_jumpers no)
		(fp_line
			(start -0.7874 -0.4064)
			(end 0.7874 -0.4064)
			(stroke
				(width 0.1524)
				(type default)
			)
			(layer "F.SilkS")
		)
		(fp_line
			(start -0.7874 0.4064)
			(end -0.7874 -0.4064)
			(stroke
				(width 0.1524)
				(type default)
			)
			(layer "F.SilkS")
		)
		(fp_line
			(start 0.7874 -0.4064)
			(end 0.7874 0.4064)
			(stroke
				(width 0.1524)
				(type default)
			)
			(layer "F.SilkS")
		)
		(fp_line
			(start 0.7874 0.4064)
			(end -0.7874 0.4064)
			(stroke
				(width 0.1524)
				(type default)
			)
			(layer "F.SilkS")
		)
		(fp_line
			(start -0.67945 -0.305054)
			(end -0.12065 -0.305054)
			(stroke
				(width 0.1)
				(type default)
			)
			(layer "F.Fab")
		)
		(fp_line
			(start -0.67945 0.3048)
			(end -0.67945 -0.305054)
			(stroke
				(width 0.1)
				(type default)
			)
			(layer "F.Fab")
		)
		(fp_line
			(start -0.12065 -0.305054)
			(end -0.12065 -0.2794)
			(stroke
				(width 0.1)
				(type default)
			)
			(layer "F.Fab")
		)
		(fp_line
			(start -0.12065 -0.2794)
			(end 0.12065 -0.2794)
			(stroke
				(width 0.1)
				(type default)
			)
			(layer "F.Fab")
		)
		(fp_line
			(start -0.12065 0.2794)
			(end -0.12065 0.3048)
			(stroke
				(width 0.1)
				(type default)
			)
			(layer "F.Fab")
		)
		(fp_line
			(start -0.12065 0.3048)
			(end -0.67945 0.3048)
			(stroke
				(width 0.1)
				(type default)
			)
			(layer "F.Fab")
		)
		(fp_line
			(start 0.120396 0.2794)
			(end -0.12065 0.2794)
			(stroke
				(width 0.1)
				(type default)
			)
			(layer "F.Fab")
		)
		(fp_line
			(start 0.120396 0.3048)
			(end 0.120396 0.2794)
			(stroke
				(width 0.1)
				(type default)
			)
			(layer "F.Fab")
		)
		(fp_line
			(start 0.12065 -0.3048)
			(end 0.67945 -0.3048)
			(stroke
				(width 0.1)
				(type default)
			)
			(layer "F.Fab")
		)
		(fp_line
			(start 0.12065 -0.2794)
			(end 0.12065 -0.3048)
			(stroke
				(width 0.1)
				(type default)
			)
			(layer "F.Fab")
		)
		(fp_line
			(start 0.67945 -0.3048)
			(end 0.67945 0.3048)
			(stroke
				(width 0.1)
				(type default)
			)
			(layer "F.Fab")
		)
		(fp_line
			(start 0.67945 0.3048)
			(end 0.120396 0.3048)
			(stroke
				(width 0.1)
				(type default)
			)
			(layer "F.Fab")
		)
		(pad "1" smd circle
			(at -0.40005 0)
			(size 0 0)
			(layers "F.Cu" "F.Mask" "F.Paste")
			(net "BOOT_RDY_R_H")
		)
		(pad "2" smd circle
			(at 0.40005 0)
			(size 0 0)
			(layers "F.Cu" "F.Mask" "F.Paste")
			(net "BOOT_RDY_H")
		)
	)
	(footprint ""
		(layer "F.Cu")
		(at 323.624194 -38.10762)
		(property "Reference" "R4568"
			(at 0 0 0)
			(layer "F.SilkS")
			(hide yes)
			(effects
				(font
					(size 1.27 1.27)
				)
			)
		)
		(property "Value" ""
			(at 0 0 0)
			(layer "F.Fab")
			(effects
				(font
					(size 1.27 1.27)
				)
			)
		)
		(duplicate_pad_numbers_are_jumpers no)
		(fp_line
			(start -0.7874 -0.4064)
			(end 0.7874 -0.4064)
			(stroke
				(width 0.1524)
				(type default)
			)
			(layer "F.SilkS")
		)
		(fp_line
			(start -0.7874 0.4064)
			(end -0.7874 -0.4064)
			(stroke
				(width 0.1524)
				(type default)
			)
			(layer "F.SilkS")
		)
		(fp_line
			(start 0.7874 -0.4064)
			(end 0.7874 0.4064)
			(stroke
				(width 0.1524)
				(type default)
			)
			(layer "F.SilkS")
		)
		(fp_line
			(start 0.7874 0.4064)
			(end -0.7874 0.4064)
			(stroke
				(width 0.1524)
				(type default)
			)
			(layer "F.SilkS")
		)
		(fp_line
			(start -0.67945 -0.305054)
			(end -0.12065 -0.305054)
			(stroke
				(width 0.1)
				(type default)
			)
			(layer "F.Fab")
		)
		(fp_line
			(start -0.67945 0.3048)
			(end -0.67945 -0.305054)
			(stroke
				(width 0.1)
				(type default)
			)
			(layer "F.Fab")
		)
		(fp_line
			(start -0.12065 -0.305054)
			(end -0.12065 -0.2794)
			(stroke
				(width 0.1)
				(type default)
			)
			(layer "F.Fab")
		)
		(fp_line
			(start -0.12065 -0.2794)
			(end 0.12065 -0.2794)
			(stroke
				(width 0.1)
				(type default)
			)
			(layer "F.Fab")
		)
		(fp_line
			(start -0.12065 0.2794)
			(end -0.12065 0.3048)
			(stroke
				(width 0.1)
				(type default)
			)
			(layer "F.Fab")
		)
		(fp_line
			(start -0.12065 0.3048)
			(end -0.67945 0.3048)
			(stroke
				(width 0.1)
				(type default)
			)
			(layer "F.Fab")
		)
		(fp_line
			(start 0.120396 0.2794)
			(end -0.12065 0.2794)
			(stroke
				(width 0.1)
				(type default)
			)
			(layer "F.Fab")
		)
		(fp_line
			(start 0.120396 0.3048)
			(end 0.120396 0.2794)
			(stroke
				(width 0.1)
				(type default)
			)
			(layer "F.Fab")
		)
		(fp_line
			(start 0.12065 -0.3048)
			(end 0.67945 -0.3048)
			(stroke
				(width 0.1)
				(type default)
			)
			(layer "F.Fab")
		)
		(fp_line
			(start 0.12065 -0.2794)
			(end 0.12065 -0.3048)
			(stroke
				(width 0.1)
				(type default)
			)
			(layer "F.Fab")
		)
		(fp_line
			(start 0.67945 -0.3048)
			(end 0.67945 0.3048)
			(stroke
				(width 0.1)
				(type default)
			)
			(layer "F.Fab")
		)
		(fp_line
			(start 0.67945 0.3048)
			(end 0.120396 0.3048)
			(stroke
				(width 0.1)
				(type default)
			)
			(layer "F.Fab")
		)
		(pad "1" smd circle
			(at -0.40005 0)
			(size 0 0)
			(layers "F.Cu" "F.Mask" "F.Paste")
			(net "P1V581_PDB_ADC")
		)
		(pad "2" smd circle
			(at 0.40005 0)
			(size 0 0)
			(layers "F.Cu" "F.Mask" "F.Paste")
			(net "GND")
		)
	)
)
